(kicad_pcb
	(version 20260206)
	(generator "pcbnew")
	(generator_version "10.0")
	(general
		(thickness 1.6)
		(legacy_teardrops no)
	)
	(paper "A4")
	(title_block
		(title "03242023_DA0F0TMBIJ0_F0T_Motherboard_J_brd_V01_OCP.brd")
		(comment 1 "Grand Teton / footprints 3349-3353 of 6105")
	)
	(layers
		(0 "F.Cu" signal "TOP")
		(4 "In1.Cu" signal "GND")
		(6 "In2.Cu" signal "IN1")
		(8 "In3.Cu" signal "GND1")
		(10 "In4.Cu" signal "IN2")
		(12 "In5.Cu" signal "GND2")
		(14 "In6.Cu" signal "IN3")
		(16 "In7.Cu" signal "GND3")
		(18 "In8.Cu" signal "VCC")
		(20 "In9.Cu" signal "VCC1")
		(22 "In10.Cu" signal "GND4")
		(24 "In11.Cu" signal "IN4")
		(26 "In12.Cu" signal "GND5")
		(28 "In13.Cu" signal "IN5")
		(30 "In14.Cu" signal "GND6")
		(32 "In15.Cu" signal "IN6")
		(34 "In16.Cu" signal "GND7")
		(2 "B.Cu" signal "BOTTOM")
		(9 "F.Adhes" user "F.Adhesive")
		(11 "B.Adhes" user "B.Adhesive")
		(13 "F.Paste" user "Package Geometry/Pastemask Top")
		(15 "B.Paste" user "Package Geometry/Pastemask Bottom")
		(5 "F.SilkS" user "Ref Des/Silkscreen Top")
		(7 "B.SilkS" user "Ref Des/Silkscreen Bottom")
		(1 "F.Mask" user "Board Geometry/Soldermask Top")
		(3 "B.Mask" user "Board Geometry/Soldermask Bottom")
		(17 "Dwgs.User" user "User.Drawings")
		(19 "Cmts.User" user "User.Comments")
		(21 "Eco1.User" user "User.Eco1")
		(23 "Eco2.User" user "User.Eco2")
		(25 "Edge.Cuts" user "Board Geometry/Outline")
		(27 "Margin" user)
		(31 "F.CrtYd" user "Package Geometry/Place Bound Top")
		(29 "B.CrtYd" user "Package Geometry/Place Bound Bottom")
		(35 "F.Fab" user "Ref Des/Assembly Top")
		(33 "B.Fab" user "Ref Des/Assembly Bottom")
	)
	(footprint ""
		(layer "F.Cu")
		(at 54.89956 -156.47797 90)
		(property "Reference" "PU50_P1_1"
			(at -0.83312 -13.79728 0)
			(unlocked yes)
			(layer "F.SilkS")
			(effects
				(font
					(size 0.7874 0.5842)
					(thickness 0.1524)
				)
				(justify left)
			)
		)
		(property "Value" ""
			(at 0 0 90)
			(layer "F.Fab")
			(effects
				(font
					(size 1.27 1.27)
				)
			)
		)
		(duplicate_pad_numbers_are_jumpers no)
		(fp_line
			(start 2.500122 -2.999994)
			(end 2.500122 -2.44348)
			(stroke
				(width 0.1524)
				(type default)
			)
			(layer "F.SilkS")
		)
		(fp_line
			(start 2.31394 -2.999994)
			(end 2.500122 -2.999994)
			(stroke
				(width 0.1524)
				(type default)
			)
			(layer "F.SilkS")
		)
		(fp_line
			(start -2.500122 -2.999994)
			(end -2.24409 -2.999994)
			(stroke
				(width 0.1524)
				(type default)
			)
			(layer "F.SilkS")
		)
		(fp_line
			(start -2.500122 -2.529078)
			(end -2.500122 -2.999994)
			(stroke
				(width 0.1524)
				(type default)
			)
			(layer "F.SilkS")
		)
		(fp_line
			(start -2.500122 0.6604)
			(end -2.500122 0.229108)
			(stroke
				(width 0.1524)
				(type default)
			)
			(layer "F.SilkS")
		)
		(fp_line
			(start 2.500122 2.339594)
			(end 2.500122 2.999994)
			(stroke
				(width 0.1524)
				(type default)
			)
			(layer "F.SilkS")
		)
		(fp_line
			(start 2.500122 2.999994)
			(end 2.2987 2.999994)
			(stroke
				(width 0.1524)
				(type default)
			)
			(layer "F.SilkS")
		)
		(fp_line
			(start -2.2987 2.999994)
			(end -2.500122 2.999994)
			(stroke
				(width 0.1524)
				(type default)
			)
			(layer "F.SilkS")
		)
		(fp_line
			(start -2.500122 2.999994)
			(end -2.500122 2.339594)
			(stroke
				(width 0.1524)
				(type default)
			)
			(layer "F.SilkS")
		)
		(fp_poly
			(pts
				(xy -5.109972 -2.793238) (xy -5.109972 -1.777238) (xy -4.093972 -2.285238)
			)
			(stroke
				(width 0)
				(type default)
			)
			(fill yes)
			(layer "F.SilkS")
		)
		(fp_line
			(start 2.500122 -2.999994)
			(end 2.500122 2.999994)
			(stroke
				(width 0.1)
				(type default)
			)
			(layer "F.Fab")
		)
		(fp_line
			(start -2.500122 -2.999994)
			(end 2.500122 -2.999994)
			(stroke
				(width 0.1)
				(type default)
			)
			(layer "F.Fab")
		)
		(fp_line
			(start 2.500122 2.999994)
			(end -2.500122 2.999994)
			(stroke
				(width 0.1)
				(type default)
			)
			(layer "F.Fab")
		)
		(fp_line
			(start -2.500122 2.999994)
			(end -2.500122 -2.999994)
			(stroke
				(width 0.1)
				(type default)
			)
			(layer "F.Fab")
		)
		(fp_poly
			(pts
				(xy -4.218432 -2.783078) (xy -4.218432 -1.767078) (xy -3.202432 -2.275078)
			)
			(stroke
				(width 0)
				(type default)
			)
			(fill yes)
			(layer "F.Fab")
		)
		(pad "1" smd rect
			(at -2.400046 -2.275078 180)
			(size 0.2286 0.6096)
			(layers "F.Cu" "F.Mask" "F.Paste")
			(net "PVCCINFAON_CPU1_VOS1")
		)
		(pad "2" smd rect
			(at -2.400046 -1.82499 180)
			(size 0.2286 0.6096)
			(layers "F.Cu" "F.Mask" "F.Paste")
			(net "GND")
		)
		(pad "3" smd rect
			(at -2.400046 -1.374902 180)
			(size 0.2286 0.6096)
			(layers "F.Cu" "F.Mask" "F.Paste")
			(net "PVCCINFAON_CPU1_VDD1")
		)
		(pad "4" smd rect
			(at -2.400046 -0.925068 180)
			(size 0.2286 0.6096)
			(layers "F.Cu" "F.Mask" "F.Paste")
			(net "PVCCFA_EHV_CPU1_PVCC")
		)
		(pad "5" smd rect
			(at -2.400046 -0.47498 180)
			(size 0.2286 0.6096)
			(layers "F.Cu" "F.Mask" "F.Paste")
			(net "GND")
		)
		(pad "6" smd rect
			(at -2.400046 -0.024892 180)
			(size 0.2286 0.6096)
			(layers "F.Cu" "F.Mask" "F.Paste")
			(net "Net_1929")
		)
		(pad "7_9-20_24" smd circle
			(at 0 1.150112 180)
			(size 0 0)
			(layers "F.Cu" "F.Mask" "F.Paste")
			(net "GND")
		)
		(pad "10_19" smd rect
			(at 0 2.899918 180)
			(size 0.6096 4.318)
			(layers "F.Cu" "F.Mask" "F.Paste")
			(net "SW_PVCCINFAON_CPU1_SW1")
		)
		(pad "25_29" smd rect
			(at 1.549908 -1.279906)
			(size 2.0574 2.3114)
			(layers "F.Cu" "F.Mask" "F.Paste")
			(net "SW_P12V_PVCCINFAON_CPU1_FLT")
		)
		(pad "30" smd rect
			(at 2.05994 -2.899918 90)
			(size 0.2286 0.6096)
			(layers "F.Cu" "F.Mask" "F.Paste")
			(net "SW_P12V_PVCCINFAON_CPU1_FLT")
		)
		(pad "31" smd rect
			(at 1.610106 -2.899918 90)
			(size 0.2286 0.6096)
			(layers "F.Cu" "F.Mask" "F.Paste")
			(net "Net_1928")
		)
		(pad "32" smd rect
			(at 1.160018 -2.899918 90)
			(size 0.2286 0.6096)
			(layers "F.Cu" "F.Mask" "F.Paste")
			(net "SW_PVCCINFAON_CPU1_BOOTR1")
		)
		(pad "33" smd rect
			(at 0.70993 -2.899918 90)
			(size 0.2286 0.6096)
			(layers "F.Cu" "F.Mask" "F.Paste")
			(net "SW_PVCCINFAON_CPU1_BOOT1")
		)
		(pad "34" smd rect
			(at 0.260096 -2.899918 90)
			(size 0.2286 0.6096)
			(layers "F.Cu" "F.Mask" "F.Paste")
			(net "PVCCINFAON_CPU1_APWM1")
		)
		(pad "35" smd rect
			(at -0.189992 -2.899918 90)
			(size 0.2286 0.6096)
			(layers "F.Cu" "F.Mask" "F.Paste")
			(net "PVCCINFAON_CPU1_VDD1")
		)
		(pad "36" smd rect
			(at -0.64008 -2.899918 90)
			(size 0.2286 0.6096)
			(layers "F.Cu" "F.Mask" "F.Paste")
			(net "PVCCINFAON_CPU1_ATSEN")
		)
		(pad "37" smd rect
			(at -1.089914 -2.899918 90)
			(size 0.2286 0.6096)
			(layers "F.Cu" "F.Mask" "F.Paste")
			(net "PVCCINFAON_CPU1_LSET1")
		)
		(pad "38" smd rect
			(at -1.540002 -2.899918 90)
			(size 0.2286 0.6096)
			(layers "F.Cu" "F.Mask" "F.Paste")
			(net "PVCCINFAON_CPU1_ACSP1")
		)
		(pad "39" smd rect
			(at -1.99009 -2.899918 90)
			(size 0.2286 0.6096)
			(layers "F.Cu" "F.Mask" "F.Paste")
			(net "PVCCINFAON_CPU1_VREF")
		)
		(pad "40" smd rect
			(at -0.87503 -1.27508 90)
			(size 1.7526 1.9558)
			(layers "F.Cu" "F.Mask" "F.Paste")
			(net "GND")
		)
		(pad "41" smd rect
			(at -1.525016 0.249936)
			(size 0.3048 0.4572)
			(layers "F.Cu" "F.Mask" "F.Paste")
			(net "Net_1930")
		)
		(zone
			(layer "F.Cu")
			(hatch none 0.5)
			(connect_pads
				(clearance 0)
			)
			(min_thickness 0.25)
			(keepout
				(tracks not_allowed)
				(vias allowed)
				(pads allowed)
				(copperpour not_allowed)
				(footprints allowed)
			)
			(placement
				(enabled no)
				(sheetname "")
			)
			(fill
				(thermal_gap 0.5)
				(thermal_bridge_width 0.5)
				(island_removal_mode 0)
			)
			(polygon
				(pts
					(xy 57.899554 -153.977848) (xy 57.391046 -153.977848) (xy 57.150254 -154.21864) (xy 57.150254 -158.767526)
					(xy 57.36082 -158.978092) (xy 57.899554 -158.978092) (xy 57.899554 -158.68777) (xy 57.443878 -158.68777)
					(xy 57.443878 -154.26817) (xy 57.899554 -154.26817)
				)
			)
		)
	)
	(footprint ""
		(layer "F.Cu")
		(at 283.413708 -411.29458 -90)
		(property "Reference" "R4557"
			(at 0 0 270)
			(layer "F.SilkS")
			(hide yes)
			(effects
				(font
					(size 1.27 1.27)
				)
			)
		)
		(property "Value" ""
			(at 0 0 270)
			(layer "F.Fab")
			(effects
				(font
					(size 1.27 1.27)
				)
			)
		)
		(duplicate_pad_numbers_are_jumpers no)
		(fp_line
			(start -0.7874 0.4064)
			(end -0.7874 -0.4064)
			(stroke
				(width 0.1524)
				(type default)
			)
			(layer "F.SilkS")
		)
		(fp_line
			(start 0.7874 0.4064)
			(end -0.7874 0.4064)
			(stroke
				(width 0.1524)
				(type default)
			)
			(layer "F.SilkS")
		)
		(fp_line
			(start -0.7874 -0.4064)
			(end 0.7874 -0.4064)
			(stroke
				(width 0.1524)
				(type default)
			)
			(layer "F.SilkS")
		)
		(fp_line
			(start 0.7874 -0.4064)
			(end 0.7874 0.4064)
			(stroke
				(width 0.1524)
				(type default)
			)
			(layer "F.SilkS")
		)
		(fp_line
			(start -0.67945 0.3048)
			(end -0.67945 -0.305054)
			(stroke
				(width 0.1)
				(type default)
			)
			(layer "F.Fab")
		)
		(fp_line
			(start -0.12065 0.3048)
			(end -0.67945 0.3048)
			(stroke
				(width 0.1)
				(type default)
			)
			(layer "F.Fab")
		)
		(fp_line
			(start 0.120396 0.3048)
			(end 0.120396 0.2794)
			(stroke
				(width 0.1)
				(type default)
			)
			(layer "F.Fab")
		)
		(fp_line
			(start 0.67945 0.3048)
			(end 0.120396 0.3048)
			(stroke
				(width 0.1)
				(type default)
			)
			(layer "F.Fab")
		)
		(fp_line
			(start -0.12065 0.2794)
			(end -0.12065 0.3048)
			(stroke
				(width 0.1)
				(type default)
			)
			(layer "F.Fab")
		)
		(fp_line
			(start 0.120396 0.2794)
			(end -0.12065 0.2794)
			(stroke
				(width 0.1)
				(type default)
			)
			(layer "F.Fab")
		)
		(fp_line
			(start -0.12065 -0.2794)
			(end 0.12065 -0.2794)
			(stroke
				(width 0.1)
				(type default)
			)
			(layer "F.Fab")
		)
		(fp_line
			(start 0.12065 -0.2794)
			(end 0.12065 -0.3048)
			(stroke
				(width 0.1)
				(type default)
			)
			(layer "F.Fab")
		)
		(fp_line
			(start 0.12065 -0.3048)
			(end 0.67945 -0.3048)
			(stroke
				(width 0.1)
				(type default)
			)
			(layer "F.Fab")
		)
		(fp_line
			(start 0.67945 -0.3048)
			(end 0.67945 0.3048)
			(stroke
				(width 0.1)
				(type default)
			)
			(layer "F.Fab")
		)
		(fp_line
			(start -0.67945 -0.305054)
			(end -0.12065 -0.305054)
			(stroke
				(width 0.1)
				(type default)
			)
			(layer "F.Fab")
		)
		(fp_line
			(start -0.12065 -0.305054)
			(end -0.12065 -0.2794)
			(stroke
				(width 0.1)
				(type default)
			)
			(layer "F.Fab")
		)
		(pad "1" smd circle
			(at -0.40005 0 270)
			(size 0 0)
			(layers "F.Cu" "F.Mask" "F.Paste")
			(net "HPDB_HSC_PWRGD_ISO")
		)
		(pad "2" smd circle
			(at 0.40005 0 270)
			(size 0 0)
			(layers "F.Cu" "F.Mask" "F.Paste")
			(net "HPDB_HSC_PWRGD_ISO_R")
		)
	)
	(footprint ""
		(layer "F.Cu")
		(at 301.136304 -426.478446 -90)
		(property "Reference" "R4126"
			(at 0 0 270)
			(layer "F.SilkS")
			(hide yes)
			(effects
				(font
					(size 1.27 1.27)
				)
			)
		)
		(property "Value" ""
			(at 0 0 270)
			(layer "F.Fab")
			(effects
				(font
					(size 1.27 1.27)
				)
			)
		)
		(duplicate_pad_numbers_are_jumpers no)
		(fp_line
			(start -0.7874 0.4064)
			(end -0.7874 -0.4064)
			(stroke
				(width 0.1524)
				(type default)
			)
			(layer "F.SilkS")
		)
		(fp_line
			(start 0.7874 0.4064)
			(end -0.7874 0.4064)
			(stroke
				(width 0.1524)
				(type default)
			)
			(layer "F.SilkS")
		)
		(fp_line
			(start -0.7874 -0.4064)
			(end 0.7874 -0.4064)
			(stroke
				(width 0.1524)
				(type default)
			)
			(layer "F.SilkS")
		)
		(fp_line
			(start 0.7874 -0.4064)
			(end 0.7874 0.4064)
			(stroke
				(width 0.1524)
				(type default)
			)
			(layer "F.SilkS")
		)
		(fp_line
			(start -0.67945 0.3048)
			(end -0.67945 -0.305054)
			(stroke
				(width 0.1)
				(type default)
			)
			(layer "F.Fab")
		)
		(fp_line
			(start -0.12065 0.3048)
			(end -0.67945 0.3048)
			(stroke
				(width 0.1)
				(type default)
			)
			(layer "F.Fab")
		)
		(fp_line
			(start 0.120396 0.3048)
			(end 0.120396 0.2794)
			(stroke
				(width 0.1)
				(type default)
			)
			(layer "F.Fab")
		)
		(fp_line
			(start 0.67945 0.3048)
			(end 0.120396 0.3048)
			(stroke
				(width 0.1)
				(type default)
			)
			(layer "F.Fab")
		)
		(fp_line
			(start -0.12065 0.2794)
			(end -0.12065 0.3048)
			(stroke
				(width 0.1)
				(type default)
			)
			(layer "F.Fab")
		)
		(fp_line
			(start 0.120396 0.2794)
			(end -0.12065 0.2794)
			(stroke
				(width 0.1)
				(type default)
			)
			(layer "F.Fab")
		)
		(fp_line
			(start -0.12065 -0.2794)
			(end 0.12065 -0.2794)
			(stroke
				(width 0.1)
				(type default)
			)
			(layer "F.Fab")
		)
		(fp_line
			(start 0.12065 -0.2794)
			(end 0.12065 -0.3048)
			(stroke
				(width 0.1)
				(type default)
			)
			(layer "F.Fab")
		)
		(fp_line
			(start 0.12065 -0.3048)
			(end 0.67945 -0.3048)
			(stroke
				(width 0.1)
				(type default)
			)
			(layer "F.Fab")
		)
		(fp_line
			(start 0.67945 -0.3048)
			(end 0.67945 0.3048)
			(stroke
				(width 0.1)
				(type default)
			)
			(layer "F.Fab")
		)
		(fp_line
			(start -0.67945 -0.305054)
			(end -0.12065 -0.305054)
			(stroke
				(width 0.1)
				(type default)
			)
			(layer "F.Fab")
		)
		(fp_line
			(start -0.12065 -0.305054)
			(end -0.12065 -0.2794)
			(stroke
				(width 0.1)
				(type default)
			)
			(layer "F.Fab")
		)
		(pad "1" smd circle
			(at -0.40005 0 270)
			(size 0 0)
			(layers "F.Cu" "F.Mask" "F.Paste")
			(net "P3V3_AUX")
		)
		(pad "2" smd circle
			(at 0.40005 0 270)
			(size 0 0)
			(layers "F.Cu" "F.Mask" "F.Paste")
			(net "PRSNT_CABLE_GPU_B3")
		)
	)
	(footprint ""
		(layer "F.Cu")
		(at 145.34388 -42.446448)
		(property "Reference" "R3295"
			(at 0 0 0)
			(layer "F.SilkS")
			(hide yes)
			(effects
				(font
					(size 1.27 1.27)
				)
			)
		)
		(property "Value" ""
			(at 0 0 0)
			(layer "F.Fab")
			(effects
				(font
					(size 1.27 1.27)
				)
			)
		)
		(duplicate_pad_numbers_are_jumpers no)
		(fp_line
			(start -0.7874 -0.4064)
			(end 0.7874 -0.4064)
			(stroke
				(width 0.1524)
				(type default)
			)
			(layer "F.SilkS")
		)
		(fp_line
			(start -0.7874 0.4064)
			(end -0.7874 -0.4064)
			(stroke
				(width 0.1524)
				(type default)
			)
			(layer "F.SilkS")
		)
		(fp_line
			(start 0.7874 -0.4064)
			(end 0.7874 0.4064)
			(stroke
				(width 0.1524)
				(type default)
			)
			(layer "F.SilkS")
		)
		(fp_line
			(start 0.7874 0.4064)
			(end -0.7874 0.4064)
			(stroke
				(width 0.1524)
				(type default)
			)
			(layer "F.SilkS")
		)
		(fp_line
			(start -0.67945 -0.305054)
			(end -0.12065 -0.305054)
			(stroke
				(width 0.1)
				(type default)
			)
			(layer "F.Fab")
		)
		(fp_line
			(start -0.67945 0.3048)
			(end -0.67945 -0.305054)
			(stroke
				(width 0.1)
				(type default)
			)
			(layer "F.Fab")
		)
		(fp_line
			(start -0.12065 -0.305054)
			(end -0.12065 -0.2794)
			(stroke
				(width 0.1)
				(type default)
			)
			(layer "F.Fab")
		)
		(fp_line
			(start -0.12065 -0.2794)
			(end 0.12065 -0.2794)
			(stroke
				(width 0.1)
				(type default)
			)
			(layer "F.Fab")
		)
		(fp_line
			(start -0.12065 0.2794)
			(end -0.12065 0.3048)
			(stroke
				(width 0.1)
				(type default)
			)
			(layer "F.Fab")
		)
		(fp_line
			(start -0.12065 0.3048)
			(end -0.67945 0.3048)
			(stroke
				(width 0.1)
				(type default)
			)
			(layer "F.Fab")
		)
		(fp_line
			(start 0.120396 0.2794)
			(end -0.12065 0.2794)
			(stroke
				(width 0.1)
				(type default)
			)
			(layer "F.Fab")
		)
		(fp_line
			(start 0.120396 0.3048)
			(end 0.120396 0.2794)
			(stroke
				(width 0.1)
				(type default)
			)
			(layer "F.Fab")
		)
		(fp_line
			(start 0.12065 -0.3048)
			(end 0.67945 -0.3048)
			(stroke
				(width 0.1)
				(type default)
			)
			(layer "F.Fab")
		)
		(fp_line
			(start 0.12065 -0.2794)
			(end 0.12065 -0.3048)
			(stroke
				(width 0.1)
				(type default)
			)
			(layer "F.Fab")
		)
		(fp_line
			(start 0.67945 -0.3048)
			(end 0.67945 0.3048)
			(stroke
				(width 0.1)
				(type default)
			)
			(layer "F.Fab")
		)
		(fp_line
			(start 0.67945 0.3048)
			(end 0.120396 0.3048)
			(stroke
				(width 0.1)
				(type default)
			)
			(layer "F.Fab")
		)
		(pad "1" smd circle
			(at -0.40005 0)
			(size 0 0)
			(layers "F.Cu" "F.Mask" "F.Paste")
			(net "P3V3_M2_0")
		)
		(pad "2" smd circle
			(at 0.40005 0)
			(size 0 0)
			(layers "F.Cu" "F.Mask" "F.Paste")
			(net "LED_HDD_ACTIVITY_N")
		)
	)
	(footprint ""
		(layer "F.Cu")
		(at 149.959314 -408.517344 -90)
		(property "Reference" "C1535"
			(at 0 0 270)
			(layer "F.SilkS")
			(hide yes)
			(effects
				(font
					(size 1.27 1.27)
				)
			)
		)
		(property "Value" ""
			(at 0 0 270)
			(layer "F.Fab")
			(effects
				(font
					(size 1.27 1.27)
				)
			)
		)
		(duplicate_pad_numbers_are_jumpers no)
		(fp_line
			(start -0.299974 0.150114)
			(end -0.299974 -0.150114)
			(stroke
				(width 0.1)
				(type default)
			)
			(layer "F.Fab")
		)
		(fp_line
			(start 0.299974 0.150114)
			(end -0.299974 0.150114)
			(stroke
				(width 0.1)
				(type default)
			)
			(layer "F.Fab")
		)
		(fp_line
			(start -0.299974 -0.150114)
			(end 0.299974 -0.150114)
			(stroke
				(width 0.1)
				(type default)
			)
			(layer "F.Fab")
		)
		(fp_line
			(start 0.299974 -0.150114)
			(end 0.299974 0.150114)
			(stroke
				(width 0.1)
				(type default)
			)
			(layer "F.Fab")
		)
		(pad "1" smd rect
			(at -0.2667 0 270)
			(size 0.3048 0.381)
			(layers "F.Cu" "F.Mask" "F.Paste")
			(net "P5E_CPU1_PE3_TX_C_DP<6>")
		)
		(pad "2" smd rect
			(at 0.2667 0 270)
			(size 0.3048 0.381)
			(layers "F.Cu" "F.Mask" "F.Paste")
			(net "P5E_CPU1_PE3_TX_DP<6>")
		)
	)
)
